(
  (version 16.5)
  (tool
    (creator "conceptHDL")
    (last "conceptHDL")
  )
  (library "mstr_symbols")
  (design "p5v_stby"
    (lastIds
      (lastNetId 4)
    )
    (nets
      ("N1" "g" -1 -1 1 3)
      ("N2" "page1_g" -1 -1 0 )
      ("N4" "page1_p5v_stby" -1 -1 0 )
      ("N3" "p5v_stby" -1 -1 2 )
    )

    (alias
      ("N2" -1 -1 "N1" -1 -1)
      ("N4" -1 -1 "N2" -1 -1)
      ("N4" -1 -1 "N3" -1 -1)
    )

  )
)
